# T6G (Grand Teton) — schematic netlist excerpt (pin names and nets, part order shuffled) for the footprints in the layout excerpt that follows; sources: Cadence DE-HDL packaged netlist, KiCad conversion of 04192023_DAF0TMB3IC0_F0TG_MB_C_brd_V02_OCP.brd

R4160  Q_RES  54.9K 1% EMPTY  pkg 0402LF  page 124 : A = P3V3_AUX ; B = GPU_3V3IO_RSVD4

PPQ9  MOSFET_NCH_1D3S  PSMNR58-30YLH IC  pkg SOT1023  page 266
  \1\  = P12V_AUX
  \2\  = P12V_AUX
  \3\  = P12V_AUX
  \4\  = MB0_CM_GATE_G0
  \5\  = P12V_MAIN_R_0

(kicad_pcb
	(version 20260206)
	(generator "pcbnew")
	(generator_version "10.0")
	(general
		(thickness 1.6)
		(legacy_teardrops no)
	)
	(paper "A4")
	(title_block
		(title "04192023_DAF0TMB3IC0_F0TG_MB_C_brd_V02_OCP.brd")
		(comment 1 "Grand Teton / footprints 1013-1014 of 8354")
	)
	(layers
		(0 "F.Cu" signal "TOP")
		(4 "In1.Cu" signal "GND")
		(6 "In2.Cu" signal "IN1")
		(8 "In3.Cu" signal "GND1")
		(10 "In4.Cu" signal "IN2")
		(12 "In5.Cu" signal "GND2")
		(14 "In6.Cu" signal "IN3")
		(16 "In7.Cu" signal "GND3")
		(18 "In8.Cu" signal "VCC")
		(20 "In9.Cu" signal "VCC1")
		(22 "In10.Cu" signal "GND4")
		(24 "In11.Cu" signal "IN4")
		(26 "In12.Cu" signal "GND5")
		(28 "In13.Cu" signal "IN5")
		(30 "In14.Cu" signal "GND6")
		(32 "In15.Cu" signal "IN6")
		(34 "In16.Cu" signal "GND7")
		(2 "B.Cu" signal "BOTTOM")
		(9 "F.Adhes" user "F.Adhesive")
		(11 "B.Adhes" user "B.Adhesive")
		(13 "F.Paste" user "Package Geometry/Pastemask Top")
		(15 "B.Paste" user "Package Geometry/Pastemask Bottom")
		(5 "F.SilkS" user "Ref Des/Silkscreen Top")
		(7 "B.SilkS" user "Ref Des/Silkscreen Bottom")
		(1 "F.Mask" user "Board Geometry/Soldermask Top")
		(3 "B.Mask" user "Board Geometry/Soldermask Bottom")
		(17 "Dwgs.User" user "User.Drawings")
		(19 "Cmts.User" user "User.Comments")
		(21 "Eco1.User" user "User.Eco1")
		(23 "Eco2.User" user "User.Eco2")
		(25 "Edge.Cuts" user "Board Geometry/Outline")
		(27 "Margin" user)
		(31 "F.CrtYd" user "Package Geometry/Place Bound Top")
		(29 "B.CrtYd" user "Package Geometry/Place Bound Bottom")
		(35 "F.Fab" user "Ref Des/Assembly Top")
		(33 "B.Fab" user "Ref Des/Assembly Bottom")
	)
	(footprint ""
		(layer "F.Cu")
		(at 439.072782 -439.12536 -90)
		(property "Reference" "R4160"
			(at 0 0 270)
			(layer "F.SilkS")
			(hide yes)
			(effects
				(font
					(size 1.27 1.27)
				)
			)
		)
		(property "Value" ""
			(at 0 0 270)
			(layer "F.Fab")
			(effects
				(font
					(size 1.27 1.27)
				)
			)
		)
		(duplicate_pad_numbers_are_jumpers no)
		(fp_line
			(start -0.7874 0.4064)
			(end -0.7874 -0.4064)
			(stroke
				(width 0.1524)
				(type default)
			)
			(layer "F.SilkS")
		)
		(fp_line
			(start 0.7874 0.4064)
			(end -0.7874 0.4064)
			(stroke
				(width 0.1524)
				(type default)
			)
			(layer "F.SilkS")
		)
		(fp_line
			(start -0.7874 -0.4064)
			(end 0.7874 -0.4064)
			(stroke
				(width 0.1524)
				(type default)
			)
			(layer "F.SilkS")
		)
		(fp_line
			(start 0.7874 -0.4064)
			(end 0.7874 0.4064)
			(stroke
				(width 0.1524)
				(type default)
			)
			(layer "F.SilkS")
		)
		(fp_line
			(start -0.67945 0.3048)
			(end -0.67945 -0.305054)
			(stroke
				(width 0.1)
				(type default)
			)
			(layer "F.Fab")
		)
		(fp_line
			(start -0.12065 0.3048)
			(end -0.67945 0.3048)
			(stroke
				(width 0.1)
				(type default)
			)
			(layer "F.Fab")
		)
		(fp_line
			(start 0.120396 0.3048)
			(end 0.120396 0.2794)
			(stroke
				(width 0.1)
				(type default)
			)
			(layer "F.Fab")
		)
		(fp_line
			(start 0.67945 0.3048)
			(end 0.120396 0.3048)
			(stroke
				(width 0.1)
				(type default)
			)
			(layer "F.Fab")
		)
		(fp_line
			(start -0.12065 0.2794)
			(end -0.12065 0.3048)
			(stroke
				(width 0.1)
				(type default)
			)
			(layer "F.Fab")
		)
		(fp_line
			(start 0.120396 0.2794)
			(end -0.12065 0.2794)
			(stroke
				(width 0.1)
				(type default)
			)
			(layer "F.Fab")
		)
		(fp_line
			(start -0.12065 -0.2794)
			(end 0.12065 -0.2794)
			(stroke
				(width 0.1)
				(type default)
			)
			(layer "F.Fab")
		)
		(fp_line
			(start 0.12065 -0.2794)
			(end 0.12065 -0.3048)
			(stroke
				(width 0.1)
				(type default)
			)
			(layer "F.Fab")
		)
		(fp_line
			(start 0.12065 -0.3048)
			(end 0.67945 -0.3048)
			(stroke
				(width 0.1)
				(type default)
			)
			(layer "F.Fab")
		)
		(fp_line
			(start 0.67945 -0.3048)
			(end 0.67945 0.3048)
			(stroke
				(width 0.1)
				(type default)
			)
			(layer "F.Fab")
		)
		(fp_line
			(start -0.67945 -0.305054)
			(end -0.12065 -0.305054)
			(stroke
				(width 0.1)
				(type default)
			)
			(layer "F.Fab")
		)
		(fp_line
			(start -0.12065 -0.305054)
			(end -0.12065 -0.2794)
			(stroke
				(width 0.1)
				(type default)
			)
			(layer "F.Fab")
		)
		(pad "1" smd circle
			(at -0.40005 0 270)
			(size 0 0)
			(layers "F.Cu" "F.Mask" "F.Paste")
			(net "P3V3_AUX")
		)
		(pad "2" smd circle
			(at 0.40005 0 270)
			(size 0 0)
			(layers "F.Cu" "F.Mask" "F.Paste")
			(net "GPU_3V3IO_RSVD4")
		)
	)
	(footprint ""
		(layer "F.Cu")
		(at 277.265892 -385.27736 90)
		(property "Reference" "PPQ9"
			(at -7.517384 -2.267712 0)
			(unlocked yes)
			(layer "F.SilkS")
			(effects
				(font
					(size 0.7874 0.5842)
					(thickness 0.1524)
				)
				(justify left)
			)
		)
		(property "Value" ""
			(at 0 0 90)
			(layer "F.Fab")
			(effects
				(font
					(size 1.27 1.27)
				)
			)
		)
		(duplicate_pad_numbers_are_jumpers no)
		(fp_line
			(start 2.350008 -2.649982)
			(end 2.350008 -2.4892)
			(stroke
				(width 0.1524)
				(type default)
			)
			(layer "F.SilkS")
		)
		(fp_line
			(start -2.350008 -2.649982)
			(end 2.350008 -2.649982)
			(stroke
				(width 0.1524)
				(type default)
			)
			(layer "F.SilkS")
		)
		(fp_line
			(start -2.350008 -2.4384)
			(end -2.350008 -2.649982)
			(stroke
				(width 0.1524)
				(type default)
			)
			(layer "F.SilkS")
		)
		(fp_line
			(start 2.350008 2.4892)
			(end 2.350008 2.649982)
			(stroke
				(width 0.1524)
				(type default)
			)
			(layer "F.SilkS")
		)
		(fp_line
			(start 2.350008 2.649982)
			(end -2.350008 2.649982)
			(stroke
				(width 0.1524)
				(type default)
			)
			(layer "F.SilkS")
		)
		(fp_line
			(start -2.350008 2.649982)
			(end -2.350008 2.413)
			(stroke
				(width 0.1524)
				(type default)
			)
			(layer "F.SilkS")
		)
		(fp_poly
			(pts
				(xy -3.440938 -3.44805) (xy -2.640838 -3.440176) (xy -3.070098 -2.40284)
			)
			(stroke
				(width 0)
				(type default)
			)
			(fill yes)
			(layer "F.SilkS")
		)
		(fp_line
			(start 2.350008 -2.649982)
			(end 2.350008 2.649982)
			(stroke
				(width 0.1)
				(type default)
			)
			(layer "F.Fab")
		)
		(fp_line
			(start -2.350008 -2.649982)
			(end 2.350008 -2.649982)
			(stroke
				(width 0.1)
				(type default)
			)
			(layer "F.Fab")
		)
		(fp_line
			(start 2.350008 2.649982)
			(end -2.350008 2.649982)
			(stroke
				(width 0.1)
				(type default)
			)
			(layer "F.Fab")
		)
		(fp_line
			(start -2.350008 2.649982)
			(end -2.350008 -2.649982)
			(stroke
				(width 0.1)
				(type default)
			)
			(layer "F.Fab")
		)
		(fp_poly
			(pts
				(xy -3.717544 -1.905) (xy -4.758944 -2.3241) (xy -4.758944 -1.524)
			)
			(stroke
				(width 0)
				(type default)
			)
			(fill yes)
			(layer "F.Fab")
		)
		(pad "1" smd rect
			(at -2.999994 -1.905)
			(size 0.7112 1.1684)
			(layers "F.Cu" "F.Mask" "F.Paste")
			(net "P12V_AUX")
		)
		(pad "2" smd rect
			(at -2.999994 -0.635)
			(size 0.7112 1.1684)
			(layers "F.Cu" "F.Mask" "F.Paste")
			(net "P12V_AUX")
		)
		(pad "3" smd rect
			(at -2.999994 0.635)
			(size 0.7112 1.1684)
			(layers "F.Cu" "F.Mask" "F.Paste")
			(net "P12V_AUX")
		)
		(pad "4" smd rect
			(at -2.999994 1.905)
			(size 0.7112 1.1684)
			(layers "F.Cu" "F.Mask" "F.Paste")
			(net "MB0_CM_GATE_G0")
		)
		(pad "5" smd circle
			(at 0.925068 0)
			(size 0 0)
			(layers "F.Cu" "F.Mask" "F.Paste")
			(net "P12V_MAIN_R_0")
		)
		(zone
			(layer "F.Cu")
			(hatch none 0.5)
			(connect_pads
				(clearance 0)
			)
			(min_thickness 0.25)
			(keepout
				(tracks not_allowed)
				(vias allowed)
				(pads allowed)
				(copperpour not_allowed)
				(footprints allowed)
			)
			(placement
				(enabled no)
				(sheetname "")
			)
			(fill
				(thermal_gap 0.5)
				(thermal_bridge_width 0.5)
				(island_removal_mode 0)
			)
			(polygon
				(pts
					(xy 274.624292 -383.7178) (xy 279.907492 -383.7178) (xy 279.907492 -382.92786) (xy 274.624292 -382.92786)
				)
			)
		)
	)
)
